(kicad_pcb
	(version 20260206)
	(generator "pcbnew")
	(generator_version "10.0")
	(general
		(thickness 1.6)
		(legacy_teardrops no)
	)
	(paper "A4")
	(title_block
		(title "01162023_DA0F0TEBIF0_F0T_Expander_BD_F_brd_V02_OCP.brd")
		(comment 1 "Grand Teton / footprints 8932-8940 of 9728")
	)
	(layers
		(0 "F.Cu" signal "TOP")
		(4 "In1.Cu" signal "GND")
		(6 "In2.Cu" signal "VCC")
		(8 "In3.Cu" signal "VCC1")
		(10 "In4.Cu" signal "GND1")
		(12 "In5.Cu" signal "IN1")
		(14 "In6.Cu" signal "GND2")
		(16 "In7.Cu" signal "IN2")
		(18 "In8.Cu" signal "GND3")
		(20 "In9.Cu" signal "IN3")
		(22 "In10.Cu" signal "GND4")
		(24 "In11.Cu" signal "IN4")
		(26 "In12.Cu" signal "GND5")
		(28 "In13.Cu" signal "IN5")
		(30 "In14.Cu" signal "GND6")
		(32 "In15.Cu" signal "IN6")
		(34 "In16.Cu" signal "GND7")
		(2 "B.Cu" signal "BOTTOM")
		(9 "F.Adhes" user "F.Adhesive")
		(11 "B.Adhes" user "B.Adhesive")
		(13 "F.Paste" user "Package Geometry/Pastemask Top")
		(15 "B.Paste" user "Package Geometry/Pastemask Bottom")
		(5 "F.SilkS" user "Ref Des/Silkscreen Top")
		(7 "B.SilkS" user "Ref Des/Silkscreen Bottom")
		(1 "F.Mask" user "Board Geometry/Soldermask Top")
		(3 "B.Mask" user "Board Geometry/Soldermask Bottom")
		(17 "Dwgs.User" user "User.Drawings")
		(19 "Cmts.User" user "User.Comments")
		(21 "Eco1.User" user "User.Eco1")
		(23 "Eco2.User" user "User.Eco2")
		(25 "Edge.Cuts" user "Board Geometry/Outline")
		(27 "Margin" user)
		(31 "F.CrtYd" user "Package Geometry/Place Bound Top")
		(29 "B.CrtYd" user "Package Geometry/Place Bound Bottom")
		(35 "F.Fab" user "Ref Des/Assembly Top")
		(33 "B.Fab" user "Ref Des/Assembly Bottom")
	)
	(footprint ""
		(layer "B.Cu")
		(at 118.611142 -325.186294 -90)
		(property "Reference" "C4268"
			(at 0 0 90)
			(layer "B.SilkS")
			(hide yes)
			(effects
				(font
					(size 1.27 1.27)
				)
				(justify mirror)
			)
		)
		(property "Value" ""
			(at 0 0 90)
			(layer "B.Fab")
			(effects
				(font
					(size 1.27 1.27)
				)
				(justify mirror)
			)
		)
		(duplicate_pad_numbers_are_jumpers no)
		(fp_line
			(start -1.2954 0.5842)
			(end 1.2954 0.5842)
			(stroke
				(width 0.1524)
				(type default)
			)
			(layer "B.SilkS")
		)
		(fp_line
			(start 1.2954 0.5842)
			(end 1.2954 -0.5842)
			(stroke
				(width 0.1524)
				(type default)
			)
			(layer "B.SilkS")
		)
		(fp_line
			(start -1.2954 -0.5842)
			(end -1.2954 0.5842)
			(stroke
				(width 0.1524)
				(type default)
			)
			(layer "B.SilkS")
		)
		(fp_line
			(start 1.2954 -0.5842)
			(end -1.2954 -0.5842)
			(stroke
				(width 0.1524)
				(type default)
			)
			(layer "B.SilkS")
		)
		(fp_line
			(start -0.8636 0.4572)
			(end 0.8636 0.4572)
			(stroke
				(width 0.1)
				(type default)
			)
			(layer "B.Fab")
		)
		(fp_line
			(start 0.8636 0.4572)
			(end 0.8636 0.4064)
			(stroke
				(width 0.1)
				(type default)
			)
			(layer "B.Fab")
		)
		(fp_line
			(start -1.1938 0.4064)
			(end -0.8636 0.4064)
			(stroke
				(width 0.1)
				(type default)
			)
			(layer "B.Fab")
		)
		(fp_line
			(start -0.8636 0.4064)
			(end -0.8636 0.4572)
			(stroke
				(width 0.1)
				(type default)
			)
			(layer "B.Fab")
		)
		(fp_line
			(start 0.8636 0.4064)
			(end 1.1938 0.4064)
			(stroke
				(width 0.1)
				(type default)
			)
			(layer "B.Fab")
		)
		(fp_line
			(start 1.1938 0.4064)
			(end 1.1938 -0.4064)
			(stroke
				(width 0.1)
				(type default)
			)
			(layer "B.Fab")
		)
		(fp_line
			(start -1.1938 -0.4064)
			(end -1.1938 0.4064)
			(stroke
				(width 0.1)
				(type default)
			)
			(layer "B.Fab")
		)
		(fp_line
			(start -0.8636 -0.4064)
			(end -1.1938 -0.4064)
			(stroke
				(width 0.1)
				(type default)
			)
			(layer "B.Fab")
		)
		(fp_line
			(start 0.8636 -0.4064)
			(end 0.8636 -0.4572)
			(stroke
				(width 0.1)
				(type default)
			)
			(layer "B.Fab")
		)
		(fp_line
			(start 1.1938 -0.4064)
			(end 0.8636 -0.4064)
			(stroke
				(width 0.1)
				(type default)
			)
			(layer "B.Fab")
		)
		(fp_line
			(start -0.8636 -0.4572)
			(end -0.8636 -0.4064)
			(stroke
				(width 0.1)
				(type default)
			)
			(layer "B.Fab")
		)
		(fp_line
			(start 0.8636 -0.4572)
			(end -0.8636 -0.4572)
			(stroke
				(width 0.1)
				(type default)
			)
			(layer "B.Fab")
		)
		(pad "1" smd rect
			(at 0.7366 0 180)
			(size 0.7112 0.8128)
			(layers "B.Cu" "B.Mask" "B.Paste")
			(net "P0V8_SERDES_VDDA_PEX1_C6")
		)
		(pad "2" smd rect
			(at -0.7366 0 180)
			(size 0.7112 0.8128)
			(layers "B.Cu" "B.Mask" "B.Paste")
			(net "GND")
		)
	)
	(footprint ""
		(layer "B.Cu")
		(at 103.172006 -357.923084 90)
		(property "Reference" "R6377"
			(at 0 0 90)
			(layer "B.SilkS")
			(hide yes)
			(effects
				(font
					(size 1.27 1.27)
				)
				(justify mirror)
			)
		)
		(property "Value" ""
			(at 0 0 90)
			(layer "B.Fab")
			(effects
				(font
					(size 1.27 1.27)
				)
				(justify mirror)
			)
		)
		(duplicate_pad_numbers_are_jumpers no)
		(fp_line
			(start 0.7874 -0.4064)
			(end -0.7874 -0.4064)
			(stroke
				(width 0.1524)
				(type default)
			)
			(layer "B.SilkS")
		)
		(fp_line
			(start -0.7874 -0.4064)
			(end -0.7874 0.4064)
			(stroke
				(width 0.1524)
				(type default)
			)
			(layer "B.SilkS")
		)
		(fp_line
			(start 0.7874 0.4064)
			(end 0.7874 -0.4064)
			(stroke
				(width 0.1524)
				(type default)
			)
			(layer "B.SilkS")
		)
		(fp_line
			(start -0.7874 0.4064)
			(end 0.7874 0.4064)
			(stroke
				(width 0.1524)
				(type default)
			)
			(layer "B.SilkS")
		)
		(fp_line
			(start 0.67945 -0.305054)
			(end 0.12065 -0.305054)
			(stroke
				(width 0.1)
				(type default)
			)
			(layer "B.Fab")
		)
		(fp_line
			(start 0.12065 -0.305054)
			(end 0.12065 -0.2794)
			(stroke
				(width 0.1)
				(type default)
			)
			(layer "B.Fab")
		)
		(fp_line
			(start -0.12065 -0.3048)
			(end -0.67945 -0.3048)
			(stroke
				(width 0.1)
				(type default)
			)
			(layer "B.Fab")
		)
		(fp_line
			(start -0.67945 -0.3048)
			(end -0.67945 0.3048)
			(stroke
				(width 0.1)
				(type default)
			)
			(layer "B.Fab")
		)
		(fp_line
			(start 0.12065 -0.2794)
			(end -0.12065 -0.2794)
			(stroke
				(width 0.1)
				(type default)
			)
			(layer "B.Fab")
		)
		(fp_line
			(start -0.12065 -0.2794)
			(end -0.12065 -0.3048)
			(stroke
				(width 0.1)
				(type default)
			)
			(layer "B.Fab")
		)
		(fp_line
			(start 0.12065 0.2794)
			(end 0.12065 0.3048)
			(stroke
				(width 0.1)
				(type default)
			)
			(layer "B.Fab")
		)
		(fp_line
			(start -0.120396 0.2794)
			(end 0.12065 0.2794)
			(stroke
				(width 0.1)
				(type default)
			)
			(layer "B.Fab")
		)
		(fp_line
			(start 0.67945 0.3048)
			(end 0.67945 -0.305054)
			(stroke
				(width 0.1)
				(type default)
			)
			(layer "B.Fab")
		)
		(fp_line
			(start 0.12065 0.3048)
			(end 0.67945 0.3048)
			(stroke
				(width 0.1)
				(type default)
			)
			(layer "B.Fab")
		)
		(fp_line
			(start -0.120396 0.3048)
			(end -0.120396 0.2794)
			(stroke
				(width 0.1)
				(type default)
			)
			(layer "B.Fab")
		)
		(fp_line
			(start -0.67945 0.3048)
			(end -0.120396 0.3048)
			(stroke
				(width 0.1)
				(type default)
			)
			(layer "B.Fab")
		)
		(pad "1" smd circle
			(at 0.40005 0 270)
			(size 0 0)
			(layers "B.Cu" "B.Mask" "B.Paste")
			(net "CLK_100M_DB800ZL_PEX1_S3_R_DN")
		)
		(pad "2" smd circle
			(at -0.40005 0 270)
			(size 0 0)
			(layers "B.Cu" "B.Mask" "B.Paste")
			(net "CLK_100M_DB800ZL_PEX1_S3_DN")
		)
	)
	(footprint ""
		(layer "B.Cu")
		(at 113.514124 -328.43343)
		(property "Reference" "R1224"
			(at 0 0 0)
			(layer "B.SilkS")
			(hide yes)
			(effects
				(font
					(size 1.27 1.27)
				)
				(justify mirror)
			)
		)
		(property "Value" ""
			(at 0 0 0)
			(layer "B.Fab")
			(effects
				(font
					(size 1.27 1.27)
				)
				(justify mirror)
			)
		)
		(duplicate_pad_numbers_are_jumpers no)
		(fp_line
			(start -0.7874 -0.4064)
			(end -0.7874 0.4064)
			(stroke
				(width 0.1524)
				(type default)
			)
			(layer "B.SilkS")
		)
		(fp_line
			(start -0.7874 0.4064)
			(end 0.7874 0.4064)
			(stroke
				(width 0.1524)
				(type default)
			)
			(layer "B.SilkS")
		)
		(fp_line
			(start 0.7874 -0.4064)
			(end -0.7874 -0.4064)
			(stroke
				(width 0.1524)
				(type default)
			)
			(layer "B.SilkS")
		)
		(fp_line
			(start 0.7874 0.4064)
			(end 0.7874 -0.4064)
			(stroke
				(width 0.1524)
				(type default)
			)
			(layer "B.SilkS")
		)
		(fp_line
			(start -0.67945 -0.3048)
			(end -0.67945 0.3048)
			(stroke
				(width 0.1)
				(type default)
			)
			(layer "B.Fab")
		)
		(fp_line
			(start -0.67945 0.3048)
			(end -0.120396 0.3048)
			(stroke
				(width 0.1)
				(type default)
			)
			(layer "B.Fab")
		)
		(fp_line
			(start -0.12065 -0.3048)
			(end -0.67945 -0.3048)
			(stroke
				(width 0.1)
				(type default)
			)
			(layer "B.Fab")
		)
		(fp_line
			(start -0.12065 -0.2794)
			(end -0.12065 -0.3048)
			(stroke
				(width 0.1)
				(type default)
			)
			(layer "B.Fab")
		)
		(fp_line
			(start -0.120396 0.2794)
			(end 0.12065 0.2794)
			(stroke
				(width 0.1)
				(type default)
			)
			(layer "B.Fab")
		)
		(fp_line
			(start -0.120396 0.3048)
			(end -0.120396 0.2794)
			(stroke
				(width 0.1)
				(type default)
			)
			(layer "B.Fab")
		)
		(fp_line
			(start 0.12065 -0.305054)
			(end 0.12065 -0.2794)
			(stroke
				(width 0.1)
				(type default)
			)
			(layer "B.Fab")
		)
		(fp_line
			(start 0.12065 -0.2794)
			(end -0.12065 -0.2794)
			(stroke
				(width 0.1)
				(type default)
			)
			(layer "B.Fab")
		)
		(fp_line
			(start 0.12065 0.2794)
			(end 0.12065 0.3048)
			(stroke
				(width 0.1)
				(type default)
			)
			(layer "B.Fab")
		)
		(fp_line
			(start 0.12065 0.3048)
			(end 0.67945 0.3048)
			(stroke
				(width 0.1)
				(type default)
			)
			(layer "B.Fab")
		)
		(fp_line
			(start 0.67945 -0.305054)
			(end 0.12065 -0.305054)
			(stroke
				(width 0.1)
				(type default)
			)
			(layer "B.Fab")
		)
		(fp_line
			(start 0.67945 0.3048)
			(end 0.67945 -0.305054)
			(stroke
				(width 0.1)
				(type default)
			)
			(layer "B.Fab")
		)
		(pad "1" smd circle
			(at 0.40005 0 180)
			(size 0 0)
			(layers "B.Cu" "B.Mask" "B.Paste")
			(net "GND")
		)
		(pad "2" smd circle
			(at -0.40005 0 180)
			(size 0 0)
			(layers "B.Cu" "B.Mask" "B.Paste")
			(net "SMB_9ZXL0451E_ADDR0")
		)
	)
	(footprint ""
		(layer "B.Cu")
		(at 411.750002 -299.699934 -90)
		(property "Reference" "C2004"
			(at 0 0 90)
			(layer "B.SilkS")
			(hide yes)
			(effects
				(font
					(size 1.27 1.27)
				)
				(justify mirror)
			)
		)
		(property "Value" ""
			(at 0 0 90)
			(layer "B.Fab")
			(effects
				(font
					(size 1.27 1.27)
				)
				(justify mirror)
			)
		)
		(duplicate_pad_numbers_are_jumpers no)
		(fp_line
			(start -0.299974 0.150114)
			(end 0.299974 0.150114)
			(stroke
				(width 0.1)
				(type default)
			)
			(layer "B.Fab")
		)
		(fp_line
			(start 0.299974 0.150114)
			(end 0.299974 -0.150114)
			(stroke
				(width 0.1)
				(type default)
			)
			(layer "B.Fab")
		)
		(fp_line
			(start -0.299974 -0.150114)
			(end -0.299974 0.150114)
			(stroke
				(width 0.1)
				(type default)
			)
			(layer "B.Fab")
		)
		(fp_line
			(start 0.299974 -0.150114)
			(end -0.299974 -0.150114)
			(stroke
				(width 0.1)
				(type default)
			)
			(layer "B.Fab")
		)
		(pad "1" smd rect
			(at 0.2667 0 90)
			(size 0.3048 0.381)
			(layers "B.Cu" "B.Mask" "B.Paste")
			(net "P0V8_SERDES_VDDA_PEX3")
		)
		(pad "2" smd rect
			(at -0.2667 0 90)
			(size 0.3048 0.381)
			(layers "B.Cu" "B.Mask" "B.Paste")
			(net "GND")
		)
	)
	(footprint ""
		(layer "B.Cu")
		(at 134.93369 -308.67604 90)
		(property "Reference" "C4250"
			(at 0 0 90)
			(layer "B.SilkS")
			(hide yes)
			(effects
				(font
					(size 1.27 1.27)
				)
				(justify mirror)
			)
		)
		(property "Value" ""
			(at 0 0 90)
			(layer "B.Fab")
			(effects
				(font
					(size 1.27 1.27)
				)
				(justify mirror)
			)
		)
		(duplicate_pad_numbers_are_jumpers no)
		(fp_line
			(start 0.299974 -0.150114)
			(end -0.299974 -0.150114)
			(stroke
				(width 0.1)
				(type default)
			)
			(layer "B.Fab")
		)
		(fp_line
			(start -0.299974 -0.150114)
			(end -0.299974 0.150114)
			(stroke
				(width 0.1)
				(type default)
			)
			(layer "B.Fab")
		)
		(fp_line
			(start 0.299974 0.150114)
			(end 0.299974 -0.150114)
			(stroke
				(width 0.1)
				(type default)
			)
			(layer "B.Fab")
		)
		(fp_line
			(start -0.299974 0.150114)
			(end 0.299974 0.150114)
			(stroke
				(width 0.1)
				(type default)
			)
			(layer "B.Fab")
		)
		(pad "1" smd rect
			(at 0.2667 0 270)
			(size 0.3048 0.381)
			(layers "B.Cu" "B.Mask" "B.Paste")
			(net "P0V8_PEX1")
		)
		(pad "2" smd rect
			(at -0.2667 0 270)
			(size 0.3048 0.381)
			(layers "B.Cu" "B.Mask" "B.Paste")
			(net "GND")
		)
	)
	(footprint ""
		(layer "B.Cu")
		(at 278.554942 -295.2623)
		(property "Reference" "C3391"
			(at 0 0 0)
			(layer "B.SilkS")
			(hide yes)
			(effects
				(font
					(size 1.27 1.27)
				)
				(justify mirror)
			)
		)
		(property "Value" ""
			(at 0 0 0)
			(layer "B.Fab")
			(effects
				(font
					(size 1.27 1.27)
				)
				(justify mirror)
			)
		)
		(duplicate_pad_numbers_are_jumpers no)
		(fp_line
			(start -0.299974 -0.150114)
			(end -0.299974 0.150114)
			(stroke
				(width 0.1)
				(type default)
			)
			(layer "B.Fab")
		)
		(fp_line
			(start -0.299974 0.150114)
			(end 0.299974 0.150114)
			(stroke
				(width 0.1)
				(type default)
			)
			(layer "B.Fab")
		)
		(fp_line
			(start 0.299974 -0.150114)
			(end -0.299974 -0.150114)
			(stroke
				(width 0.1)
				(type default)
			)
			(layer "B.Fab")
		)
		(fp_line
			(start 0.299974 0.150114)
			(end 0.299974 -0.150114)
			(stroke
				(width 0.1)
				(type default)
			)
			(layer "B.Fab")
		)
		(pad "1" smd rect
			(at 0.2667 0 180)
			(size 0.3048 0.381)
			(layers "B.Cu" "B.Mask" "B.Paste")
			(net "PCEPLL4_VDDA18_PEX2")
		)
		(pad "2" smd rect
			(at -0.2667 0 180)
			(size 0.3048 0.381)
			(layers "B.Cu" "B.Mask" "B.Paste")
			(net "GND")
		)
	)
	(footprint ""
		(layer "B.Cu")
		(at 125.570488 -283.818584 90)
		(property "Reference" "PR107"
			(at 0 0 90)
			(layer "B.SilkS")
			(hide yes)
			(effects
				(font
					(size 1.27 1.27)
				)
				(justify mirror)
			)
		)
		(property "Value" ""
			(at 0 0 90)
			(layer "B.Fab")
			(effects
				(font
					(size 1.27 1.27)
				)
				(justify mirror)
			)
		)
		(duplicate_pad_numbers_are_jumpers no)
		(fp_line
			(start 0.7874 -0.4064)
			(end -0.7874 -0.4064)
			(stroke
				(width 0.1524)
				(type default)
			)
			(layer "B.SilkS")
		)
		(fp_line
			(start -0.7874 -0.4064)
			(end -0.7874 0.4064)
			(stroke
				(width 0.1524)
				(type default)
			)
			(layer "B.SilkS")
		)
		(fp_line
			(start 0.7874 0.4064)
			(end 0.7874 -0.4064)
			(stroke
				(width 0.1524)
				(type default)
			)
			(layer "B.SilkS")
		)
		(fp_line
			(start -0.7874 0.4064)
			(end 0.7874 0.4064)
			(stroke
				(width 0.1524)
				(type default)
			)
			(layer "B.SilkS")
		)
		(fp_line
			(start 0.67945 -0.305054)
			(end 0.12065 -0.305054)
			(stroke
				(width 0.1)
				(type default)
			)
			(layer "B.Fab")
		)
		(fp_line
			(start 0.12065 -0.305054)
			(end 0.12065 -0.2794)
			(stroke
				(width 0.1)
				(type default)
			)
			(layer "B.Fab")
		)
		(fp_line
			(start -0.12065 -0.3048)
			(end -0.67945 -0.3048)
			(stroke
				(width 0.1)
				(type default)
			)
			(layer "B.Fab")
		)
		(fp_line
			(start -0.67945 -0.3048)
			(end -0.67945 0.3048)
			(stroke
				(width 0.1)
				(type default)
			)
			(layer "B.Fab")
		)
		(fp_line
			(start 0.12065 -0.2794)
			(end -0.12065 -0.2794)
			(stroke
				(width 0.1)
				(type default)
			)
			(layer "B.Fab")
		)
		(fp_line
			(start -0.12065 -0.2794)
			(end -0.12065 -0.3048)
			(stroke
				(width 0.1)
				(type default)
			)
			(layer "B.Fab")
		)
		(fp_line
			(start 0.12065 0.2794)
			(end 0.12065 0.3048)
			(stroke
				(width 0.1)
				(type default)
			)
			(layer "B.Fab")
		)
		(fp_line
			(start -0.120396 0.2794)
			(end 0.12065 0.2794)
			(stroke
				(width 0.1)
				(type default)
			)
			(layer "B.Fab")
		)
		(fp_line
			(start 0.67945 0.3048)
			(end 0.67945 -0.305054)
			(stroke
				(width 0.1)
				(type default)
			)
			(layer "B.Fab")
		)
		(fp_line
			(start 0.12065 0.3048)
			(end 0.67945 0.3048)
			(stroke
				(width 0.1)
				(type default)
			)
			(layer "B.Fab")
		)
		(fp_line
			(start -0.120396 0.3048)
			(end -0.120396 0.2794)
			(stroke
				(width 0.1)
				(type default)
			)
			(layer "B.Fab")
		)
		(fp_line
			(start -0.67945 0.3048)
			(end -0.120396 0.3048)
			(stroke
				(width 0.1)
				(type default)
			)
			(layer "B.Fab")
		)
		(pad "1" smd circle
			(at 0.40005 0 270)
			(size 0 0)
			(layers "B.Cu" "B.Mask" "B.Paste")
			(net "P0V8_PEX1_PVCC")
		)
		(pad "2" smd circle
			(at -0.40005 0 270)
			(size 0 0)
			(layers "B.Cu" "B.Mask" "B.Paste")
			(net "P0V8_PEX1_VCC1")
		)
	)
	(footprint ""
		(layer "B.Cu")
		(at 288.049716 -299.699934 -90)
		(property "Reference" "C1729"
			(at 0 0 90)
			(layer "B.SilkS")
			(hide yes)
			(effects
				(font
					(size 1.27 1.27)
				)
				(justify mirror)
			)
		)
		(property "Value" ""
			(at 0 0 90)
			(layer "B.Fab")
			(effects
				(font
					(size 1.27 1.27)
				)
				(justify mirror)
			)
		)
		(duplicate_pad_numbers_are_jumpers no)
		(fp_line
			(start -0.299974 0.150114)
			(end 0.299974 0.150114)
			(stroke
				(width 0.1)
				(type default)
			)
			(layer "B.Fab")
		)
		(fp_line
			(start 0.299974 0.150114)
			(end 0.299974 -0.150114)
			(stroke
				(width 0.1)
				(type default)
			)
			(layer "B.Fab")
		)
		(fp_line
			(start -0.299974 -0.150114)
			(end -0.299974 0.150114)
			(stroke
				(width 0.1)
				(type default)
			)
			(layer "B.Fab")
		)
		(fp_line
			(start 0.299974 -0.150114)
			(end -0.299974 -0.150114)
			(stroke
				(width 0.1)
				(type default)
			)
			(layer "B.Fab")
		)
		(pad "1" smd rect
			(at 0.2667 0 90)
			(size 0.3048 0.381)
			(layers "B.Cu" "B.Mask" "B.Paste")
			(net "P0V8_SERDES_VDDA_PEX2")
		)
		(pad "2" smd rect
			(at -0.2667 0 90)
			(size 0.3048 0.381)
			(layers "B.Cu" "B.Mask" "B.Paste")
			(net "GND")
		)
	)
	(footprint ""
		(layer "B.Cu")
		(at 118.456964 -318.542416)
		(property "Reference" "C4253"
			(at 0 0 0)
			(layer "B.SilkS")
			(hide yes)
			(effects
				(font
					(size 1.27 1.27)
				)
				(justify mirror)
			)
		)
		(property "Value" ""
			(at 0 0 0)
			(layer "B.Fab")
			(effects
				(font
					(size 1.27 1.27)
				)
				(justify mirror)
			)
		)
		(duplicate_pad_numbers_are_jumpers no)
		(fp_line
			(start -0.299974 -0.150114)
			(end -0.299974 0.150114)
			(stroke
				(width 0.1)
				(type default)
			)
			(layer "B.Fab")
		)
		(fp_line
			(start -0.299974 0.150114)
			(end 0.299974 0.150114)
			(stroke
				(width 0.1)
				(type default)
			)
			(layer "B.Fab")
		)
		(fp_line
			(start 0.299974 -0.150114)
			(end -0.299974 -0.150114)
			(stroke
				(width 0.1)
				(type default)
			)
			(layer "B.Fab")
		)
		(fp_line
			(start 0.299974 0.150114)
			(end 0.299974 -0.150114)
			(stroke
				(width 0.1)
				(type default)
			)
			(layer "B.Fab")
		)
		(pad "1" smd rect
			(at 0.2667 0 180)
			(size 0.3048 0.381)
			(layers "B.Cu" "B.Mask" "B.Paste")
			(net "P0V8_SERDES_VDDA_PEX1")
		)
		(pad "2" smd rect
			(at -0.2667 0 180)
			(size 0.3048 0.381)
			(layers "B.Cu" "B.Mask" "B.Paste")
			(net "GND")
		)
	)
)
